(kicad_pcb
	(version 20260206)
	(generator "pcbnew")
	(generator_version "10.0")
	(general
		(thickness 1.6)
		(legacy_teardrops no)
	)
	(paper "A4")
	(title_block
		(title "04192023_DAF0TMB3IC0_F0TG_MB_C_brd_V02_OCP.brd")
		(comment 1 "Grand Teton / footprints 704-711 of 8354")
	)
	(layers
		(0 "F.Cu" signal "TOP")
		(4 "In1.Cu" signal "GND")
		(6 "In2.Cu" signal "IN1")
		(8 "In3.Cu" signal "GND1")
		(10 "In4.Cu" signal "IN2")
		(12 "In5.Cu" signal "GND2")
		(14 "In6.Cu" signal "IN3")
		(16 "In7.Cu" signal "GND3")
		(18 "In8.Cu" signal "VCC")
		(20 "In9.Cu" signal "VCC1")
		(22 "In10.Cu" signal "GND4")
		(24 "In11.Cu" signal "IN4")
		(26 "In12.Cu" signal "GND5")
		(28 "In13.Cu" signal "IN5")
		(30 "In14.Cu" signal "GND6")
		(32 "In15.Cu" signal "IN6")
		(34 "In16.Cu" signal "GND7")
		(2 "B.Cu" signal "BOTTOM")
		(9 "F.Adhes" user "F.Adhesive")
		(11 "B.Adhes" user "B.Adhesive")
		(13 "F.Paste" user "Package Geometry/Pastemask Top")
		(15 "B.Paste" user "Package Geometry/Pastemask Bottom")
		(5 "F.SilkS" user "Ref Des/Silkscreen Top")
		(7 "B.SilkS" user "Ref Des/Silkscreen Bottom")
		(1 "F.Mask" user "Board Geometry/Soldermask Top")
		(3 "B.Mask" user "Board Geometry/Soldermask Bottom")
		(17 "Dwgs.User" user "User.Drawings")
		(19 "Cmts.User" user "User.Comments")
		(21 "Eco1.User" user "User.Eco1")
		(23 "Eco2.User" user "User.Eco2")
		(25 "Edge.Cuts" user "Board Geometry/Outline")
		(27 "Margin" user)
		(31 "F.CrtYd" user "Package Geometry/Place Bound Top")
		(29 "B.CrtYd" user "Package Geometry/Place Bound Bottom")
		(35 "F.Fab" user "Ref Des/Assembly Top")
		(33 "B.Fab" user "Ref Des/Assembly Bottom")
	)
	(footprint ""
		(layer "F.Cu")
		(at 146.567398 -49.153064)
		(property "Reference" "R1346"
			(at 0 0 0)
			(layer "F.SilkS")
			(hide yes)
			(effects
				(font
					(size 1.27 1.27)
				)
			)
		)
		(property "Value" ""
			(at 0 0 0)
			(layer "F.Fab")
			(effects
				(font
					(size 1.27 1.27)
				)
			)
		)
		(duplicate_pad_numbers_are_jumpers no)
		(fp_line
			(start -0.7874 -0.4064)
			(end 0.7874 -0.4064)
			(stroke
				(width 0.1524)
				(type default)
			)
			(layer "F.SilkS")
		)
		(fp_line
			(start -0.7874 0.4064)
			(end -0.7874 -0.4064)
			(stroke
				(width 0.1524)
				(type default)
			)
			(layer "F.SilkS")
		)
		(fp_line
			(start 0.7874 -0.4064)
			(end 0.7874 0.4064)
			(stroke
				(width 0.1524)
				(type default)
			)
			(layer "F.SilkS")
		)
		(fp_line
			(start 0.7874 0.4064)
			(end -0.7874 0.4064)
			(stroke
				(width 0.1524)
				(type default)
			)
			(layer "F.SilkS")
		)
		(fp_line
			(start -0.67945 -0.305054)
			(end -0.12065 -0.305054)
			(stroke
				(width 0.1)
				(type default)
			)
			(layer "F.Fab")
		)
		(fp_line
			(start -0.67945 0.3048)
			(end -0.67945 -0.305054)
			(stroke
				(width 0.1)
				(type default)
			)
			(layer "F.Fab")
		)
		(fp_line
			(start -0.12065 -0.305054)
			(end -0.12065 -0.2794)
			(stroke
				(width 0.1)
				(type default)
			)
			(layer "F.Fab")
		)
		(fp_line
			(start -0.12065 -0.2794)
			(end 0.12065 -0.2794)
			(stroke
				(width 0.1)
				(type default)
			)
			(layer "F.Fab")
		)
		(fp_line
			(start -0.12065 0.2794)
			(end -0.12065 0.3048)
			(stroke
				(width 0.1)
				(type default)
			)
			(layer "F.Fab")
		)
		(fp_line
			(start -0.12065 0.3048)
			(end -0.67945 0.3048)
			(stroke
				(width 0.1)
				(type default)
			)
			(layer "F.Fab")
		)
		(fp_line
			(start 0.120396 0.2794)
			(end -0.12065 0.2794)
			(stroke
				(width 0.1)
				(type default)
			)
			(layer "F.Fab")
		)
		(fp_line
			(start 0.120396 0.3048)
			(end 0.120396 0.2794)
			(stroke
				(width 0.1)
				(type default)
			)
			(layer "F.Fab")
		)
		(fp_line
			(start 0.12065 -0.3048)
			(end 0.67945 -0.3048)
			(stroke
				(width 0.1)
				(type default)
			)
			(layer "F.Fab")
		)
		(fp_line
			(start 0.12065 -0.2794)
			(end 0.12065 -0.3048)
			(stroke
				(width 0.1)
				(type default)
			)
			(layer "F.Fab")
		)
		(fp_line
			(start 0.67945 -0.3048)
			(end 0.67945 0.3048)
			(stroke
				(width 0.1)
				(type default)
			)
			(layer "F.Fab")
		)
		(fp_line
			(start 0.67945 0.3048)
			(end 0.120396 0.3048)
			(stroke
				(width 0.1)
				(type default)
			)
			(layer "F.Fab")
		)
		(pad "1" smd circle
			(at -0.40005 0)
			(size 0 0)
			(layers "F.Cu" "F.Mask" "F.Paste")
			(net "SMB_INA230_3V3AUX_SCL")
		)
		(pad "2" smd circle
			(at 0.40005 0)
			(size 0 0)
			(layers "F.Cu" "F.Mask" "F.Paste")
			(net "SMB_INA230_7_3V3AUX_SCL_R")
		)
	)
	(footprint ""
		(layer "F.Cu")
		(at 329.592178 -41.160954 180)
		(property "Reference" "R2907"
			(at 0 0 180)
			(layer "F.SilkS")
			(hide yes)
			(effects
				(font
					(size 1.27 1.27)
				)
			)
		)
		(property "Value" ""
			(at 0 0 180)
			(layer "F.Fab")
			(effects
				(font
					(size 1.27 1.27)
				)
			)
		)
		(duplicate_pad_numbers_are_jumpers no)
		(fp_line
			(start 0.7874 0.4064)
			(end -0.7874 0.4064)
			(stroke
				(width 0.1524)
				(type default)
			)
			(layer "F.SilkS")
		)
		(fp_line
			(start 0.7874 -0.4064)
			(end 0.7874 0.4064)
			(stroke
				(width 0.1524)
				(type default)
			)
			(layer "F.SilkS")
		)
		(fp_line
			(start -0.7874 0.4064)
			(end -0.7874 -0.4064)
			(stroke
				(width 0.1524)
				(type default)
			)
			(layer "F.SilkS")
		)
		(fp_line
			(start -0.7874 -0.4064)
			(end 0.7874 -0.4064)
			(stroke
				(width 0.1524)
				(type default)
			)
			(layer "F.SilkS")
		)
		(fp_line
			(start 0.67945 0.3048)
			(end 0.120396 0.3048)
			(stroke
				(width 0.1)
				(type default)
			)
			(layer "F.Fab")
		)
		(fp_line
			(start 0.67945 -0.3048)
			(end 0.67945 0.3048)
			(stroke
				(width 0.1)
				(type default)
			)
			(layer "F.Fab")
		)
		(fp_line
			(start 0.12065 -0.2794)
			(end 0.12065 -0.3048)
			(stroke
				(width 0.1)
				(type default)
			)
			(layer "F.Fab")
		)
		(fp_line
			(start 0.12065 -0.3048)
			(end 0.67945 -0.3048)
			(stroke
				(width 0.1)
				(type default)
			)
			(layer "F.Fab")
		)
		(fp_line
			(start 0.120396 0.3048)
			(end 0.120396 0.2794)
			(stroke
				(width 0.1)
				(type default)
			)
			(layer "F.Fab")
		)
		(fp_line
			(start 0.120396 0.2794)
			(end -0.12065 0.2794)
			(stroke
				(width 0.1)
				(type default)
			)
			(layer "F.Fab")
		)
		(fp_line
			(start -0.12065 0.3048)
			(end -0.67945 0.3048)
			(stroke
				(width 0.1)
				(type default)
			)
			(layer "F.Fab")
		)
		(fp_line
			(start -0.12065 0.2794)
			(end -0.12065 0.3048)
			(stroke
				(width 0.1)
				(type default)
			)
			(layer "F.Fab")
		)
		(fp_line
			(start -0.12065 -0.2794)
			(end 0.12065 -0.2794)
			(stroke
				(width 0.1)
				(type default)
			)
			(layer "F.Fab")
		)
		(fp_line
			(start -0.12065 -0.305054)
			(end -0.12065 -0.2794)
			(stroke
				(width 0.1)
				(type default)
			)
			(layer "F.Fab")
		)
		(fp_line
			(start -0.67945 0.3048)
			(end -0.67945 -0.305054)
			(stroke
				(width 0.1)
				(type default)
			)
			(layer "F.Fab")
		)
		(fp_line
			(start -0.67945 -0.305054)
			(end -0.12065 -0.305054)
			(stroke
				(width 0.1)
				(type default)
			)
			(layer "F.Fab")
		)
		(pad "1" smd circle
			(at -0.40005 0 180)
			(size 0 0)
			(layers "F.Cu" "F.Mask" "F.Paste")
			(net "P3V3_AUX")
		)
		(pad "2" smd circle
			(at 0.40005 0 180)
			(size 0 0)
			(layers "F.Cu" "F.Mask" "F.Paste")
			(net "P3V3_AUX_ADC")
		)
	)
	(footprint ""
		(layer "F.Cu")
		(at 185.777124 -96.096074 -90)
		(property "Reference" "R1187"
			(at 0 0 270)
			(layer "F.SilkS")
			(hide yes)
			(effects
				(font
					(size 1.27 1.27)
				)
			)
		)
		(property "Value" ""
			(at 0 0 270)
			(layer "F.Fab")
			(effects
				(font
					(size 1.27 1.27)
				)
			)
		)
		(duplicate_pad_numbers_are_jumpers no)
		(fp_line
			(start -0.7874 0.4064)
			(end -0.7874 -0.4064)
			(stroke
				(width 0.1524)
				(type default)
			)
			(layer "F.SilkS")
		)
		(fp_line
			(start 0.7874 0.4064)
			(end -0.7874 0.4064)
			(stroke
				(width 0.1524)
				(type default)
			)
			(layer "F.SilkS")
		)
		(fp_line
			(start -0.7874 -0.4064)
			(end 0.7874 -0.4064)
			(stroke
				(width 0.1524)
				(type default)
			)
			(layer "F.SilkS")
		)
		(fp_line
			(start 0.7874 -0.4064)
			(end 0.7874 0.4064)
			(stroke
				(width 0.1524)
				(type default)
			)
			(layer "F.SilkS")
		)
		(fp_line
			(start -0.67945 0.3048)
			(end -0.67945 -0.305054)
			(stroke
				(width 0.1)
				(type default)
			)
			(layer "F.Fab")
		)
		(fp_line
			(start -0.12065 0.3048)
			(end -0.67945 0.3048)
			(stroke
				(width 0.1)
				(type default)
			)
			(layer "F.Fab")
		)
		(fp_line
			(start 0.120396 0.3048)
			(end 0.120396 0.2794)
			(stroke
				(width 0.1)
				(type default)
			)
			(layer "F.Fab")
		)
		(fp_line
			(start 0.67945 0.3048)
			(end 0.120396 0.3048)
			(stroke
				(width 0.1)
				(type default)
			)
			(layer "F.Fab")
		)
		(fp_line
			(start -0.12065 0.2794)
			(end -0.12065 0.3048)
			(stroke
				(width 0.1)
				(type default)
			)
			(layer "F.Fab")
		)
		(fp_line
			(start 0.120396 0.2794)
			(end -0.12065 0.2794)
			(stroke
				(width 0.1)
				(type default)
			)
			(layer "F.Fab")
		)
		(fp_line
			(start -0.12065 -0.2794)
			(end 0.12065 -0.2794)
			(stroke
				(width 0.1)
				(type default)
			)
			(layer "F.Fab")
		)
		(fp_line
			(start 0.12065 -0.2794)
			(end 0.12065 -0.3048)
			(stroke
				(width 0.1)
				(type default)
			)
			(layer "F.Fab")
		)
		(fp_line
			(start 0.12065 -0.3048)
			(end 0.67945 -0.3048)
			(stroke
				(width 0.1)
				(type default)
			)
			(layer "F.Fab")
		)
		(fp_line
			(start 0.67945 -0.3048)
			(end 0.67945 0.3048)
			(stroke
				(width 0.1)
				(type default)
			)
			(layer "F.Fab")
		)
		(fp_line
			(start -0.67945 -0.305054)
			(end -0.12065 -0.305054)
			(stroke
				(width 0.1)
				(type default)
			)
			(layer "F.Fab")
		)
		(fp_line
			(start -0.12065 -0.305054)
			(end -0.12065 -0.2794)
			(stroke
				(width 0.1)
				(type default)
			)
			(layer "F.Fab")
		)
		(pad "1" smd circle
			(at -0.40005 0 270)
			(size 0 0)
			(layers "F.Cu" "F.Mask" "F.Paste")
			(net "PVDDCR_CPU0_P1_PMALERT")
		)
		(pad "2" smd circle
			(at 0.40005 0 270)
			(size 0 0)
			(layers "F.Cu" "F.Mask" "F.Paste")
			(net "P3V3_AUX")
		)
	)
	(footprint ""
		(layer "F.Cu")
		(at 243.063268 -44.682918)
		(property "Reference" "C1277"
			(at 0 0 0)
			(layer "F.SilkS")
			(hide yes)
			(effects
				(font
					(size 1.27 1.27)
				)
			)
		)
		(property "Value" ""
			(at 0 0 0)
			(layer "F.Fab")
			(effects
				(font
					(size 1.27 1.27)
				)
			)
		)
		(duplicate_pad_numbers_are_jumpers no)
		(fp_line
			(start -1.524 -0.762)
			(end 1.524 -0.762)
			(stroke
				(width 0.1524)
				(type default)
			)
			(layer "F.SilkS")
		)
		(fp_line
			(start -1.524 0.762)
			(end -1.524 -0.762)
			(stroke
				(width 0.1524)
				(type default)
			)
			(layer "F.SilkS")
		)
		(fp_line
			(start 1.524 -0.762)
			(end 1.524 0.762)
			(stroke
				(width 0.1524)
				(type default)
			)
			(layer "F.SilkS")
		)
		(fp_line
			(start 1.524 0.762)
			(end -1.524 0.762)
			(stroke
				(width 0.1524)
				(type default)
			)
			(layer "F.SilkS")
		)
		(fp_line
			(start -1.1049 -0.724916)
			(end -1.1049 0.724916)
			(stroke
				(width 0.1)
				(type default)
			)
			(layer "F.Fab")
		)
		(fp_line
			(start -1.1049 0.724916)
			(end 1.1049 0.724916)
			(stroke
				(width 0.1)
				(type default)
			)
			(layer "F.Fab")
		)
		(fp_line
			(start 1.1049 -0.724916)
			(end -1.1049 -0.724916)
			(stroke
				(width 0.1)
				(type default)
			)
			(layer "F.Fab")
		)
		(fp_line
			(start 1.1049 0.724916)
			(end 1.1049 -0.724916)
			(stroke
				(width 0.1)
				(type default)
			)
			(layer "F.Fab")
		)
		(pad "1" smd rect
			(at -0.889 0 180)
			(size 1.016 1.27)
			(layers "F.Cu" "F.Mask" "F.Paste")
			(net "P12V_E1S_0_R")
		)
		(pad "2" smd rect
			(at 0.889 0 180)
			(size 1.016 1.27)
			(layers "F.Cu" "F.Mask" "F.Paste")
			(net "GND")
		)
	)
	(footprint ""
		(layer "F.Cu")
		(at 19.508724 -405.868378 -90)
		(property "Reference" "C107"
			(at 0 0 270)
			(layer "F.SilkS")
			(hide yes)
			(effects
				(font
					(size 1.27 1.27)
				)
			)
		)
		(property "Value" ""
			(at 0 0 270)
			(layer "F.Fab")
			(effects
				(font
					(size 1.27 1.27)
				)
			)
		)
		(duplicate_pad_numbers_are_jumpers no)
		(fp_line
			(start -0.7874 0.4064)
			(end -0.7874 -0.4064)
			(stroke
				(width 0.1524)
				(type default)
			)
			(layer "F.SilkS")
		)
		(fp_line
			(start 0.7874 0.4064)
			(end -0.7874 0.4064)
			(stroke
				(width 0.1524)
				(type default)
			)
			(layer "F.SilkS")
		)
		(fp_line
			(start -0.7874 -0.4064)
			(end 0.7874 -0.4064)
			(stroke
				(width 0.1524)
				(type default)
			)
			(layer "F.SilkS")
		)
		(fp_line
			(start 0.7874 -0.4064)
			(end 0.7874 0.4064)
			(stroke
				(width 0.1524)
				(type default)
			)
			(layer "F.SilkS")
		)
		(fp_line
			(start -0.67945 0.3048)
			(end -0.67945 -0.305054)
			(stroke
				(width 0.1)
				(type default)
			)
			(layer "F.Fab")
		)
		(fp_line
			(start -0.12065 0.3048)
			(end -0.67945 0.3048)
			(stroke
				(width 0.1)
				(type default)
			)
			(layer "F.Fab")
		)
		(fp_line
			(start 0.120396 0.3048)
			(end 0.120396 0.2794)
			(stroke
				(width 0.1)
				(type default)
			)
			(layer "F.Fab")
		)
		(fp_line
			(start 0.67945 0.3048)
			(end 0.120396 0.3048)
			(stroke
				(width 0.1)
				(type default)
			)
			(layer "F.Fab")
		)
		(fp_line
			(start -0.12065 0.2794)
			(end -0.12065 0.3048)
			(stroke
				(width 0.1)
				(type default)
			)
			(layer "F.Fab")
		)
		(fp_line
			(start 0.120396 0.2794)
			(end -0.12065 0.2794)
			(stroke
				(width 0.1)
				(type default)
			)
			(layer "F.Fab")
		)
		(fp_line
			(start -0.12065 -0.2794)
			(end 0.12065 -0.2794)
			(stroke
				(width 0.1)
				(type default)
			)
			(layer "F.Fab")
		)
		(fp_line
			(start 0.12065 -0.2794)
			(end 0.12065 -0.3048)
			(stroke
				(width 0.1)
				(type default)
			)
			(layer "F.Fab")
		)
		(fp_line
			(start 0.12065 -0.3048)
			(end 0.67945 -0.3048)
			(stroke
				(width 0.1)
				(type default)
			)
			(layer "F.Fab")
		)
		(fp_line
			(start 0.67945 -0.3048)
			(end 0.67945 0.3048)
			(stroke
				(width 0.1)
				(type default)
			)
			(layer "F.Fab")
		)
		(fp_line
			(start -0.67945 -0.305054)
			(end -0.12065 -0.305054)
			(stroke
				(width 0.1)
				(type default)
			)
			(layer "F.Fab")
		)
		(fp_line
			(start -0.12065 -0.305054)
			(end -0.12065 -0.2794)
			(stroke
				(width 0.1)
				(type default)
			)
			(layer "F.Fab")
		)
		(pad "1" smd circle
			(at -0.40005 0 270)
			(size 0 0)
			(layers "F.Cu" "F.Mask" "F.Paste")
			(net "PWRGD_P0V9_RETIMER_CPU1_R")
		)
		(pad "2" smd circle
			(at 0.40005 0 270)
			(size 0 0)
			(layers "F.Cu" "F.Mask" "F.Paste")
			(net "GND")
		)
	)
	(footprint ""
		(layer "F.Cu")
		(at 424.5356 -421.64 90)
		(property "Reference" "R1485"
			(at 0 0 90)
			(layer "F.SilkS")
			(hide yes)
			(effects
				(font
					(size 1.27 1.27)
				)
			)
		)
		(property "Value" ""
			(at 0 0 90)
			(layer "F.Fab")
			(effects
				(font
					(size 1.27 1.27)
				)
			)
		)
		(duplicate_pad_numbers_are_jumpers no)
		(fp_line
			(start 0.32512 -0.175006)
			(end 0.32512 0.175006)
			(stroke
				(width 0.1)
				(type default)
			)
			(layer "F.Fab")
		)
		(fp_line
			(start -0.32512 -0.175006)
			(end 0.32512 -0.175006)
			(stroke
				(width 0.1)
				(type default)
			)
			(layer "F.Fab")
		)
		(fp_line
			(start 0.32512 0.175006)
			(end -0.32512 0.175006)
			(stroke
				(width 0.1)
				(type default)
			)
			(layer "F.Fab")
		)
		(fp_line
			(start -0.32512 0.175006)
			(end -0.32512 -0.175006)
			(stroke
				(width 0.1)
				(type default)
			)
			(layer "F.Fab")
		)
		(pad "1" smd rect
			(at -0.2667 0 90)
			(size 0.3048 0.381)
			(layers "F.Cu" "F.Mask" "F.Paste")
			(net "P1V8_CPU0_RT_1D")
		)
		(pad "2" smd rect
			(at 0.2667 0 270)
			(size 0.3048 0.381)
			(layers "F.Cu" "F.Mask" "F.Paste")
			(net "JTAG_TCK_RT_CPU0_P3")
		)
	)
	(footprint ""
		(layer "F.Cu")
		(at 393.715748 -17.624298 90)
		(property "Reference" "C1792"
			(at 0 0 90)
			(layer "F.SilkS")
			(hide yes)
			(effects
				(font
					(size 1.27 1.27)
				)
			)
		)
		(property "Value" ""
			(at 0 0 90)
			(layer "F.Fab")
			(effects
				(font
					(size 1.27 1.27)
				)
			)
		)
		(duplicate_pad_numbers_are_jumpers no)
		(fp_line
			(start 0.299974 -0.150114)
			(end 0.299974 0.150114)
			(stroke
				(width 0.1)
				(type default)
			)
			(layer "F.Fab")
		)
		(fp_line
			(start -0.299974 -0.150114)
			(end 0.299974 -0.150114)
			(stroke
				(width 0.1)
				(type default)
			)
			(layer "F.Fab")
		)
		(fp_line
			(start 0.299974 0.150114)
			(end -0.299974 0.150114)
			(stroke
				(width 0.1)
				(type default)
			)
			(layer "F.Fab")
		)
		(fp_line
			(start -0.299974 0.150114)
			(end -0.299974 -0.150114)
			(stroke
				(width 0.1)
				(type default)
			)
			(layer "F.Fab")
		)
		(pad "1" smd rect
			(at -0.2667 0 90)
			(size 0.3048 0.381)
			(layers "F.Cu" "F.Mask" "F.Paste")
			(net "P5E_CPU0_G3_TX_C_DP<14>")
		)
		(pad "2" smd rect
			(at 0.2667 0 90)
			(size 0.3048 0.381)
			(layers "F.Cu" "F.Mask" "F.Paste")
			(net "P5E_CPU0_G3_TX_DP<14>")
		)
	)
	(footprint ""
		(layer "F.Cu")
		(at 420.017956 -369.275106 90)
		(property "Reference" "R6856"
			(at 0 0 90)
			(layer "F.SilkS")
			(hide yes)
			(effects
				(font
					(size 1.27 1.27)
				)
			)
		)
		(property "Value" ""
			(at 0 0 90)
			(layer "F.Fab")
			(effects
				(font
					(size 1.27 1.27)
				)
			)
		)
		(duplicate_pad_numbers_are_jumpers no)
		(fp_line
			(start 0.7874 -0.4064)
			(end 0.7874 0.4064)
			(stroke
				(width 0.1524)
				(type default)
			)
			(layer "F.SilkS")
		)
		(fp_line
			(start -0.7874 -0.4064)
			(end 0.7874 -0.4064)
			(stroke
				(width 0.1524)
				(type default)
			)
			(layer "F.SilkS")
		)
		(fp_line
			(start 0.7874 0.4064)
			(end -0.7874 0.4064)
			(stroke
				(width 0.1524)
				(type default)
			)
			(layer "F.SilkS")
		)
		(fp_line
			(start -0.7874 0.4064)
			(end -0.7874 -0.4064)
			(stroke
				(width 0.1524)
				(type default)
			)
			(layer "F.SilkS")
		)
		(fp_line
			(start -0.12065 -0.305054)
			(end -0.12065 -0.2794)
			(stroke
				(width 0.1)
				(type default)
			)
			(layer "F.Fab")
		)
		(fp_line
			(start -0.67945 -0.305054)
			(end -0.12065 -0.305054)
			(stroke
				(width 0.1)
				(type default)
			)
			(layer "F.Fab")
		)
		(fp_line
			(start 0.67945 -0.3048)
			(end 0.67945 0.3048)
			(stroke
				(width 0.1)
				(type default)
			)
			(layer "F.Fab")
		)
		(fp_line
			(start 0.12065 -0.3048)
			(end 0.67945 -0.3048)
			(stroke
				(width 0.1)
				(type default)
			)
			(layer "F.Fab")
		)
		(fp_line
			(start 0.12065 -0.2794)
			(end 0.12065 -0.3048)
			(stroke
				(width 0.1)
				(type default)
			)
			(layer "F.Fab")
		)
		(fp_line
			(start -0.12065 -0.2794)
			(end 0.12065 -0.2794)
			(stroke
				(width 0.1)
				(type default)
			)
			(layer "F.Fab")
		)
		(fp_line
			(start 0.120396 0.2794)
			(end -0.12065 0.2794)
			(stroke
				(width 0.1)
				(type default)
			)
			(layer "F.Fab")
		)
		(fp_line
			(start -0.12065 0.2794)
			(end -0.12065 0.3048)
			(stroke
				(width 0.1)
				(type default)
			)
			(layer "F.Fab")
		)
		(fp_line
			(start 0.67945 0.3048)
			(end 0.120396 0.3048)
			(stroke
				(width 0.1)
				(type default)
			)
			(layer "F.Fab")
		)
		(fp_line
			(start 0.120396 0.3048)
			(end 0.120396 0.2794)
			(stroke
				(width 0.1)
				(type default)
			)
			(layer "F.Fab")
		)
		(fp_line
			(start -0.12065 0.3048)
			(end -0.67945 0.3048)
			(stroke
				(width 0.1)
				(type default)
			)
			(layer "F.Fab")
		)
		(fp_line
			(start -0.67945 0.3048)
			(end -0.67945 -0.305054)
			(stroke
				(width 0.1)
				(type default)
			)
			(layer "F.Fab")
		)
		(pad "1" smd circle
			(at -0.40005 0 90)
			(size 0 0)
			(layers "F.Cu" "F.Mask" "F.Paste")
			(net "SMB_SCM_2_R6_SCL")
		)
		(pad "2" smd circle
			(at 0.40005 0 90)
			(size 0 0)
			(layers "F.Cu" "F.Mask" "F.Paste")
			(net "P0V9_RETIMER_CPU0_PMSCL")
		)
	)
)
